(kicad_pcb
	(version 20260206)
	(generator "pcbnew")
	(generator_version "10.0")
	(general
		(thickness 1.6)
		(legacy_teardrops no)
	)
	(paper "A4")
	(title_block
		(title "Wiwynn_Tioga_Pass_MB.brd")
		(comment 1 "Tioga Pass / footprints 4351-4357 of 4770")
	)
	(layers
		(0 "F.Cu" signal "TOP")
		(4 "In1.Cu" signal "L2GND")
		(6 "In2.Cu" signal "L3")
		(8 "In3.Cu" signal "L4GND")
		(10 "In4.Cu" signal "L5")
		(12 "In5.Cu" signal "L6GND")
		(14 "In6.Cu" signal "L7VCC")
		(16 "In7.Cu" signal "L8VCC")
		(18 "In8.Cu" signal "L9GND")
		(20 "In9.Cu" signal "L10")
		(22 "In10.Cu" signal "L11GND")
		(24 "In11.Cu" signal "L12")
		(26 "In12.Cu" signal "L13GND")
		(2 "B.Cu" signal "BOTTOM")
		(9 "F.Adhes" user "F.Adhesive")
		(11 "B.Adhes" user "B.Adhesive")
		(13 "F.Paste" user "Package Geometry/Pastemask Top")
		(15 "B.Paste" user "Package Geometry/Pastemask Bottom")
		(5 "F.SilkS" user "Ref Des/Silkscreen Top")
		(7 "B.SilkS" user "Ref Des/Silkscreen Bottom")
		(1 "F.Mask" user "Board Geometry/Soldermask Top")
		(3 "B.Mask" user "Board Geometry/Soldermask Bottom")
		(17 "Dwgs.User" user "User.Drawings")
		(19 "Cmts.User" user "User.Comments")
		(21 "Eco1.User" user "User.Eco1")
		(23 "Eco2.User" user "User.Eco2")
		(25 "Edge.Cuts" user "Board Geometry/Outline")
		(27 "Margin" user)
		(31 "F.CrtYd" user "Package Geometry/Place Bound Top")
		(29 "B.CrtYd" user "Package Geometry/Place Bound Bottom")
		(35 "F.Fab" user "Ref Des/Assembly Top")
		(33 "B.Fab" user "Ref Des/Assembly Bottom")
	)
	(footprint ""
		(layer "B.Cu")
		(at 349.4024 -109.474 -90)
		(property "Reference" "C3N14"
			(at 3.58267 0.4064 0)
			(unlocked yes)
			(layer "B.SilkS")
			(effects
				(font
					(size 0.7874 0.5842)
					(thickness 0.1524)
				)
				(justify mirror)
			)
		)
		(property "Value" ""
			(at 0 0 90)
			(layer "B.Fab")
			(effects
				(font
					(size 1.27 1.27)
				)
				(justify mirror)
			)
		)
		(duplicate_pad_numbers_are_jumpers no)
		(fp_line
			(start -2.286 7.366)
			(end -1.600708 7.366)
			(stroke
				(width 0.1524)
				(type default)
			)
			(layer "B.SilkS")
		)
		(fp_line
			(start -2.286 7.366)
			(end -2.286 1.63195)
			(stroke
				(width 0.1524)
				(type default)
			)
			(layer "B.SilkS")
		)
		(fp_line
			(start 2.286 7.366)
			(end 1.60147 7.366)
			(stroke
				(width 0.1524)
				(type default)
			)
			(layer "B.SilkS")
		)
		(fp_line
			(start 2.286 7.366)
			(end 2.286 1.632712)
			(stroke
				(width 0.1524)
				(type default)
			)
			(layer "B.SilkS")
		)
		(fp_line
			(start -2.504948 1.633728)
			(end -1.6002 1.633728)
			(stroke
				(width 0.1524)
				(type default)
			)
			(layer "B.SilkS")
		)
		(fp_line
			(start 2.563114 1.633728)
			(end 1.6002 1.633728)
			(stroke
				(width 0.1524)
				(type default)
			)
			(layer "B.SilkS")
		)
		(fp_line
			(start -2.504948 -1.616456)
			(end -2.504948 1.633728)
			(stroke
				(width 0.1524)
				(type default)
			)
			(layer "B.SilkS")
		)
		(fp_line
			(start -1.6002 -1.616456)
			(end -2.504948 -1.616456)
			(stroke
				(width 0.1524)
				(type default)
			)
			(layer "B.SilkS")
		)
		(fp_line
			(start 1.6002 -1.616456)
			(end 2.563114 -1.616456)
			(stroke
				(width 0.1524)
				(type default)
			)
			(layer "B.SilkS")
		)
		(fp_line
			(start 2.563114 -1.616456)
			(end 2.563114 1.633728)
			(stroke
				(width 0.1524)
				(type default)
			)
			(layer "B.SilkS")
		)
		(fp_rect
			(start 2.286 7.366)
			(end -2.286 -0.254)
			(stroke
				(width 0)
				(type default)
			)
			(fill no)
			(layer "B.CrtYd")
		)
		(fp_line
			(start -2.286 7.366)
			(end 2.286 7.366)
			(stroke
				(width 0.1)
				(type default)
			)
			(layer "B.Fab")
		)
		(fp_line
			(start 2.286 7.366)
			(end 2.286 -0.254)
			(stroke
				(width 0.1)
				(type default)
			)
			(layer "B.Fab")
		)
		(fp_line
			(start -2.286 -0.254)
			(end -2.286 7.366)
			(stroke
				(width 0.1)
				(type default)
			)
			(layer "B.Fab")
		)
		(fp_line
			(start 2.286 -0.254)
			(end -2.286 -0.254)
			(stroke
				(width 0.1)
				(type default)
			)
			(layer "B.Fab")
		)
		(pad "1" smd rect
			(at 0 0 90)
			(size 2.54 3.048)
			(layers "B.Cu" "B.Mask" "B.Paste")
			(net "PVCCIOMCP_CPU0")
		)
		(pad "2" smd rect
			(at 0 7.112 90)
			(size 2.54 3.048)
			(layers "B.Cu" "B.Mask" "B.Paste")
			(net "GND")
		)
	)
	(footprint ""
		(layer "B.Cu")
		(at 411.791658 -11.877802 -90)
		(property "Reference" "R2R9"
			(at 0 0 90)
			(layer "B.SilkS")
			(hide yes)
			(effects
				(font
					(size 1.27 1.27)
				)
				(justify mirror)
			)
		)
		(property "Value" ""
			(at 0 0 90)
			(layer "B.Fab")
			(effects
				(font
					(size 1.27 1.27)
				)
				(justify mirror)
			)
		)
		(duplicate_pad_numbers_are_jumpers no)
		(fp_poly
			(pts
				(xy 0.2794 -0.1016) (xy -0.2794 -0.1016) (xy -0.2794 0.9906) (xy 0.2794 0.9906)
			)
			(stroke
				(width 0)
				(type default)
			)
			(fill no)
			(layer "B.CrtYd")
		)
		(fp_line
			(start -0.2794 0.9906)
			(end -0.2794 -0.1016)
			(stroke
				(width 0.1)
				(type default)
			)
			(layer "B.Fab")
		)
		(fp_line
			(start 0.2794 0.9906)
			(end -0.2794 0.9906)
			(stroke
				(width 0.1)
				(type default)
			)
			(layer "B.Fab")
		)
		(fp_line
			(start -0.2794 -0.1016)
			(end 0.2794 -0.1016)
			(stroke
				(width 0.1)
				(type default)
			)
			(layer "B.Fab")
		)
		(fp_line
			(start 0.2794 -0.1016)
			(end 0.2794 0.9906)
			(stroke
				(width 0.1)
				(type default)
			)
			(layer "B.Fab")
		)
		(pad "1" smd rect
			(at 0 0 90)
			(size 0.508 0.508)
			(layers "B.Cu" "B.Mask" "B.Paste")
			(net "FP_NMI_BTN_OUT_R_N")
		)
		(pad "2" smd rect
			(at 0 0.889 90)
			(size 0.508 0.508)
			(layers "B.Cu" "B.Mask" "B.Paste")
			(net "FP_NMI_BTN_OUT_N")
		)
		(zone
			(layer "B.Cu")
			(hatch none 0.5)
			(connect_pads
				(clearance 0)
			)
			(min_thickness 0.25)
			(keepout
				(tracks not_allowed)
				(vias allowed)
				(pads allowed)
				(copperpour not_allowed)
				(footprints allowed)
			)
			(placement
				(enabled no)
				(sheetname "")
			)
			(fill
				(thermal_gap 0.5)
				(thermal_bridge_width 0.5)
				(island_removal_mode 0)
			)
			(polygon
				(pts
					(xy 411.156658 -11.623802) (xy 411.156658 -12.131802) (xy 411.537658 -12.131802) (xy 411.537658 -11.623802)
				)
			)
		)
		(zone
			(layer "B.Cu")
			(hatch none 0.5)
			(connect_pads
				(clearance 0)
			)
			(min_thickness 0.25)
			(keepout
				(tracks allowed)
				(vias not_allowed)
				(pads allowed)
				(copperpour not_allowed)
				(footprints allowed)
			)
			(placement
				(enabled no)
				(sheetname "")
			)
			(fill
				(thermal_gap 0.5)
				(thermal_bridge_width 0.5)
				(island_removal_mode 0)
			)
			(polygon
				(pts
					(xy 411.537658 -11.623802) (xy 411.537658 -12.131802) (xy 411.156658 -12.131802) (xy 411.156658 -11.623802)
				)
			)
		)
	)
	(footprint ""
		(layer "B.Cu")
		(at 265.864086 -77.82814)
		(property "Reference" "C5P23"
			(at 0 0 0)
			(layer "B.SilkS")
			(hide yes)
			(effects
				(font
					(size 1.27 1.27)
				)
				(justify mirror)
			)
		)
		(property "Value" ""
			(at 0 0 0)
			(layer "B.Fab")
			(effects
				(font
					(size 1.27 1.27)
				)
				(justify mirror)
			)
		)
		(duplicate_pad_numbers_are_jumpers no)
		(fp_poly
			(pts
				(xy 0.7239 -0.2159) (xy -0.7239 -0.2159) (xy -0.7239 1.9939) (xy 0.7239 1.9939)
			)
			(stroke
				(width 0)
				(type default)
			)
			(fill no)
			(layer "B.CrtYd")
		)
		(fp_line
			(start -0.7239 -0.2159)
			(end 0.7239 -0.2159)
			(stroke
				(width 0.1)
				(type default)
			)
			(layer "B.Fab")
		)
		(fp_line
			(start -0.7239 1.9939)
			(end -0.7239 -0.2159)
			(stroke
				(width 0.1)
				(type default)
			)
			(layer "B.Fab")
		)
		(fp_line
			(start 0.7239 -0.2159)
			(end 0.7239 1.9939)
			(stroke
				(width 0.1)
				(type default)
			)
			(layer "B.Fab")
		)
		(fp_line
			(start 0.7239 1.9939)
			(end -0.7239 1.9939)
			(stroke
				(width 0.1)
				(type default)
			)
			(layer "B.Fab")
		)
		(pad "1" smd rect
			(at 0 0 180)
			(size 1.27 1.016)
			(layers "B.Cu" "B.Mask" "B.Paste")
			(net "PVCCIN_CPU0")
		)
		(pad "2" smd rect
			(at 0 1.778 180)
			(size 1.27 1.016)
			(layers "B.Cu" "B.Mask" "B.Paste")
			(net "GND")
		)
		(zone
			(layer "B.Cu")
			(hatch none 0.5)
			(connect_pads
				(clearance 0)
			)
			(min_thickness 0.25)
			(keepout
				(tracks not_allowed)
				(vias allowed)
				(pads allowed)
				(copperpour not_allowed)
				(footprints allowed)
			)
			(placement
				(enabled no)
				(sheetname "")
			)
			(fill
				(thermal_gap 0.5)
				(thermal_bridge_width 0.5)
				(island_removal_mode 0)
			)
			(polygon
				(pts
					(xy 266.499086 -77.32014) (xy 265.229086 -77.32014) (xy 265.229086 -76.55814) (xy 266.499086 -76.55814)
				)
			)
		)
	)
	(footprint ""
		(layer "B.Cu")
		(at 318.543432 -135.382 -90)
		(property "Reference" "C4M4"
			(at 0 0 90)
			(layer "B.SilkS")
			(hide yes)
			(effects
				(font
					(size 1.27 1.27)
				)
				(justify mirror)
			)
		)
		(property "Value" ""
			(at 0 0 90)
			(layer "B.Fab")
			(effects
				(font
					(size 1.27 1.27)
				)
				(justify mirror)
			)
		)
		(duplicate_pad_numbers_are_jumpers no)
		(fp_poly
			(pts
				(xy 0.4953 -0.2032) (xy -0.4953 -0.2032) (xy -0.4953 1.6002) (xy 0.4953 1.6002)
			)
			(stroke
				(width 0)
				(type default)
			)
			(fill no)
			(layer "B.CrtYd")
		)
		(fp_line
			(start -0.4953 1.6002)
			(end 0.4953 1.6002)
			(stroke
				(width 0.1)
				(type default)
			)
			(layer "B.Fab")
		)
		(fp_line
			(start 0.4953 1.6002)
			(end 0.4953 -0.2032)
			(stroke
				(width 0.1)
				(type default)
			)
			(layer "B.Fab")
		)
		(fp_line
			(start -0.4953 -0.2032)
			(end -0.4953 1.6002)
			(stroke
				(width 0.1)
				(type default)
			)
			(layer "B.Fab")
		)
		(fp_line
			(start 0.4953 -0.2032)
			(end -0.4953 -0.2032)
			(stroke
				(width 0.1)
				(type default)
			)
			(layer "B.Fab")
		)
		(pad "1" smd rect
			(at 0 0 90)
			(size 0.762 0.889)
			(layers "B.Cu" "B.Mask" "B.Paste")
			(net "PVPP_DEF")
		)
		(pad "2" smd rect
			(at 0 1.397 90)
			(size 0.762 0.889)
			(layers "B.Cu" "B.Mask" "B.Paste")
			(net "GND")
		)
		(zone
			(layer "B.Cu")
			(hatch none 0.5)
			(connect_pads
				(clearance 0)
			)
			(min_thickness 0.25)
			(keepout
				(tracks not_allowed)
				(vias allowed)
				(pads allowed)
				(copperpour not_allowed)
				(footprints allowed)
			)
			(placement
				(enabled no)
				(sheetname "")
			)
			(fill
				(thermal_gap 0.5)
				(thermal_bridge_width 0.5)
				(island_removal_mode 0)
			)
			(polygon
				(pts
					(xy 318.098932 -135.001) (xy 318.098932 -135.763) (xy 317.590932 -135.763) (xy 317.590932 -135.001)
				)
			)
		)
	)
	(footprint ""
		(layer "B.Cu")
		(at 195.5546 -135.3312 90)
		(property "Reference" "C6M1"
			(at 0 0 90)
			(layer "B.SilkS")
			(hide yes)
			(effects
				(font
					(size 1.27 1.27)
				)
				(justify mirror)
			)
		)
		(property "Value" ""
			(at 0 0 90)
			(layer "B.Fab")
			(effects
				(font
					(size 1.27 1.27)
				)
				(justify mirror)
			)
		)
		(duplicate_pad_numbers_are_jumpers no)
		(fp_poly
			(pts
				(xy -0.3048 -0.1016) (xy -0.3048 0.9906) (xy 0.3048 0.9906) (xy 0.3048 -0.1016)
			)
			(stroke
				(width 0)
				(type default)
			)
			(fill no)
			(layer "B.CrtYd")
		)
		(fp_line
			(start 0.3048 -0.1016)
			(end 0.3048 0.9906)
			(stroke
				(width 0.1)
				(type default)
			)
			(layer "B.Fab")
		)
		(fp_line
			(start -0.3048 -0.1016)
			(end 0.3048 -0.1016)
			(stroke
				(width 0.1)
				(type default)
			)
			(layer "B.Fab")
		)
		(fp_line
			(start 0.3048 0.9906)
			(end -0.3048 0.9906)
			(stroke
				(width 0.1)
				(type default)
			)
			(layer "B.Fab")
		)
		(fp_line
			(start -0.3048 0.9906)
			(end -0.3048 -0.1016)
			(stroke
				(width 0.1)
				(type default)
			)
			(layer "B.Fab")
		)
		(pad "1" smd rect
			(at 0 0 270)
			(size 0.508 0.508)
			(layers "B.Cu" "B.Mask" "B.Paste")
			(net "M_D_VREF")
		)
		(pad "2" smd rect
			(at 0 0.889 270)
			(size 0.508 0.508)
			(layers "B.Cu" "B.Mask" "B.Paste")
			(net "GND")
		)
		(zone
			(layer "B.Cu")
			(hatch none 0.5)
			(connect_pads
				(clearance 0)
			)
			(min_thickness 0.25)
			(keepout
				(tracks allowed)
				(vias not_allowed)
				(pads allowed)
				(copperpour not_allowed)
				(footprints allowed)
			)
			(placement
				(enabled no)
				(sheetname "")
			)
			(fill
				(thermal_gap 0.5)
				(thermal_bridge_width 0.5)
				(island_removal_mode 0)
			)
			(polygon
				(pts
					(xy 195.8086 -135.5852) (xy 195.8086 -135.0772) (xy 196.1896 -135.0772) (xy 196.1896 -135.5852)
				)
			)
		)
		(zone
			(layer "B.Cu")
			(hatch none 0.5)
			(connect_pads
				(clearance 0)
			)
			(min_thickness 0.25)
			(keepout
				(tracks not_allowed)
				(vias allowed)
				(pads allowed)
				(copperpour not_allowed)
				(footprints allowed)
			)
			(placement
				(enabled no)
				(sheetname "")
			)
			(fill
				(thermal_gap 0.5)
				(thermal_bridge_width 0.5)
				(island_removal_mode 0)
			)
			(polygon
				(pts
					(xy 196.1896 -135.5852) (xy 196.1896 -135.0772) (xy 195.8086 -135.0772) (xy 195.8086 -135.5852)
				)
			)
		)
	)
	(footprint ""
		(layer "B.Cu")
		(at 434.132482 -147.504658 -90)
		(property "Reference" "R2L21"
			(at 0 0 90)
			(layer "B.SilkS")
			(hide yes)
			(effects
				(font
					(size 1.27 1.27)
				)
				(justify mirror)
			)
		)
		(property "Value" ""
			(at 0 0 90)
			(layer "B.Fab")
			(effects
				(font
					(size 1.27 1.27)
				)
				(justify mirror)
			)
		)
		(duplicate_pad_numbers_are_jumpers no)
		(fp_poly
			(pts
				(xy 0.2794 -0.1016) (xy -0.2794 -0.1016) (xy -0.2794 0.9906) (xy 0.2794 0.9906)
			)
			(stroke
				(width 0)
				(type default)
			)
			(fill no)
			(layer "B.CrtYd")
		)
		(fp_line
			(start -0.2794 0.9906)
			(end -0.2794 -0.1016)
			(stroke
				(width 0.1)
				(type default)
			)
			(layer "B.Fab")
		)
		(fp_line
			(start 0.2794 0.9906)
			(end -0.2794 0.9906)
			(stroke
				(width 0.1)
				(type default)
			)
			(layer "B.Fab")
		)
		(fp_line
			(start -0.2794 -0.1016)
			(end 0.2794 -0.1016)
			(stroke
				(width 0.1)
				(type default)
			)
			(layer "B.Fab")
		)
		(fp_line
			(start 0.2794 -0.1016)
			(end 0.2794 0.9906)
			(stroke
				(width 0.1)
				(type default)
			)
			(layer "B.Fab")
		)
		(pad "1" smd rect
			(at 0 0 90)
			(size 0.508 0.508)
			(layers "B.Cu" "B.Mask" "B.Paste")
			(net "P3V3")
		)
		(pad "2" smd rect
			(at 0 0.889 90)
			(size 0.508 0.508)
			(layers "B.Cu" "B.Mask" "B.Paste")
			(net "PU_DATAIN1_SATA_0_R")
		)
		(zone
			(layer "B.Cu")
			(hatch none 0.5)
			(connect_pads
				(clearance 0)
			)
			(min_thickness 0.25)
			(keepout
				(tracks not_allowed)
				(vias allowed)
				(pads allowed)
				(copperpour not_allowed)
				(footprints allowed)
			)
			(placement
				(enabled no)
				(sheetname "")
			)
			(fill
				(thermal_gap 0.5)
				(thermal_bridge_width 0.5)
				(island_removal_mode 0)
			)
			(polygon
				(pts
					(xy 433.497482 -147.250658) (xy 433.497482 -147.758658) (xy 433.878482 -147.758658) (xy 433.878482 -147.250658)
				)
			)
		)
		(zone
			(layer "B.Cu")
			(hatch none 0.5)
			(connect_pads
				(clearance 0)
			)
			(min_thickness 0.25)
			(keepout
				(tracks allowed)
				(vias not_allowed)
				(pads allowed)
				(copperpour not_allowed)
				(footprints allowed)
			)
			(placement
				(enabled no)
				(sheetname "")
			)
			(fill
				(thermal_gap 0.5)
				(thermal_bridge_width 0.5)
				(island_removal_mode 0)
			)
			(polygon
				(pts
					(xy 433.878482 -147.250658) (xy 433.878482 -147.758658) (xy 433.497482 -147.758658) (xy 433.497482 -147.250658)
				)
			)
		)
	)
	(footprint ""
		(layer "B.Cu")
		(at 314.760102 -29.511752 90)
		(property "Reference" "Q8W1"
			(at 0 -1.2065 90)
			(unlocked yes)
			(layer "B.SilkS")
			(effects
				(font
					(size 1.27 0.9652)
					(thickness 0.1524)
				)
				(justify left mirror)
			)
		)
		(property "Value" ""
			(at 0 0 90)
			(layer "B.Fab")
			(effects
				(font
					(size 1.27 1.27)
				)
				(justify mirror)
			)
		)
		(duplicate_pad_numbers_are_jumpers no)
		(fp_circle
			(center 0.603758 -0.604266)
			(end 0.603758 -0.477266)
			(stroke
				(width 0.254)
				(type default)
			)
			(fill no)
			(layer "B.SilkS")
		)
		(fp_poly
			(pts
				(xy -0.21463 -0.450088) (xy -1.56337 -0.450088) (xy -1.56337 1.75006) (xy -0.21463 1.75006)
			)
			(stroke
				(width 0)
				(type default)
			)
			(fill no)
			(layer "B.CrtYd")
		)
		(fp_line
			(start -0.21463 -0.450088)
			(end -1.56337 -0.450088)
			(stroke
				(width 0.1)
				(type default)
			)
			(layer "B.Fab")
		)
		(fp_line
			(start -1.56337 -0.450088)
			(end -1.56337 1.75006)
			(stroke
				(width 0.1)
				(type default)
			)
			(layer "B.Fab")
		)
		(fp_line
			(start -0.21463 1.75006)
			(end -0.21463 -0.450088)
			(stroke
				(width 0.1)
				(type default)
			)
			(layer "B.Fab")
		)
		(fp_line
			(start -1.56337 1.75006)
			(end -0.21463 1.75006)
			(stroke
				(width 0.1)
				(type default)
			)
			(layer "B.Fab")
		)
		(fp_circle
			(center 0.848614 -0.6477)
			(end 0.848614 -0.5207)
			(stroke
				(width 0.254)
				(type default)
			)
			(fill no)
			(layer "B.Fab")
		)
		(pad "1" smd rect
			(at 0 0 270)
			(size 1.016 0.381)
			(layers "B.Cu" "B.Mask" "B.Paste")
			(net "GND")
		)
		(pad "2" smd rect
			(at 0 0.649986 270)
			(size 1.016 0.381)
			(layers "B.Cu" "B.Mask" "B.Paste")
			(net "IRQ_DIMM_SAVE_LVT3_CPU1")
		)
		(pad "3" smd rect
			(at 0 1.299972 270)
			(size 1.016 0.381)
			(layers "B.Cu" "B.Mask" "B.Paste")
			(net "IRQ_DIMM_SAVE_LVT3_CPU1")
		)
		(pad "4" smd rect
			(at -1.778 1.299972 270)
			(size 1.016 0.381)
			(layers "B.Cu" "B.Mask" "B.Paste")
			(net "GND")
		)
		(pad "5" smd rect
			(at -1.778 0.649986 270)
			(size 1.016 0.381)
			(layers "B.Cu" "B.Mask" "B.Paste")
			(net "IRQ_DIMM_SAVE_CPU1_R_N")
		)
		(pad "6" smd rect
			(at -1.778 0 270)
			(size 1.016 0.381)
			(layers "B.Cu" "B.Mask" "B.Paste")
			(net "IRQ_DIMM_SAVE_LVT3_N")
		)
	)
)
